(kicad_pcb
	(version 20260206)
	(generator "pcbnew")
	(generator_version "10.0")
	(general
		(thickness 1.6)
		(legacy_teardrops no)
	)
	(paper "A4")
	(title_block
		(title "dpb — 14545-sa.0730WZS0815.brd")
		(comment 1 "Honey Badger (Wiwynn) / footprints 408-415 of 1066")
	)
	(layers
		(0 "F.Cu" signal "TOP")
		(4 "In1.Cu" signal "L2GND")
		(6 "In2.Cu" signal "L3")
		(8 "In3.Cu" signal "L4VCC")
		(10 "In4.Cu" signal "L5VCC")
		(12 "In5.Cu" signal "L6")
		(14 "In6.Cu" signal "L7GND")
		(2 "B.Cu" signal "BOTTOM")
		(9 "F.Adhes" user "F.Adhesive")
		(11 "B.Adhes" user "B.Adhesive")
		(13 "F.Paste" user "Package Geometry/Pastemask Top")
		(15 "B.Paste" user "Package Geometry/Pastemask Bottom")
		(5 "F.SilkS" user "Ref Des/Silkscreen Top")
		(7 "B.SilkS" user "Ref Des/Silkscreen Bottom")
		(1 "F.Mask" user "Board Geometry/Soldermask Top")
		(3 "B.Mask" user "Board Geometry/Soldermask Bottom")
		(17 "Dwgs.User" user "User.Drawings")
		(19 "Cmts.User" user "User.Comments")
		(21 "Eco1.User" user "User.Eco1")
		(23 "Eco2.User" user "User.Eco2")
		(25 "Edge.Cuts" user "Board Geometry/Outline")
		(27 "Margin" user)
		(31 "F.CrtYd" user "Package Geometry/Place Bound Top")
		(29 "B.CrtYd" user "Package Geometry/Place Bound Bottom")
		(35 "F.Fab" user "Ref Des/Assembly Top")
		(33 "B.Fab" user "Ref Des/Assembly Bottom")
	)
	(footprint ""
		(layer "F.Cu")
		(at 207.391 -72.263)
		(property "Reference" "C368"
			(at 0 0 0)
			(layer "F.SilkS")
			(hide yes)
			(effects
				(font
					(size 1.27 1.27)
				)
			)
		)
		(property "Value" "SCD033U25V2KX-GP"
			(at 1.1811 -2.7051 0)
			(unlocked yes)
			(layer "F.Fab")
			(hide yes)
			(effects
				(font
					(size 1.016 1.016)
					(thickness 0.1524)
				)
			)
		)
		(property "Device Type" "C402H22"
			(at 1.1811 -4.2291 0)
			(unlocked yes)
			(layer "F.Fab")
			(hide yes)
			(effects
				(font
					(size 1.016 1.016)
					(thickness 0.1524)
				)
			)
		)
		(duplicate_pad_numbers_are_jumpers no)
		(fp_rect
			(start -0.4318 0.9525)
			(end 0.4318 -0.9525)
			(stroke
				(width 0)
				(type default)
			)
			(fill no)
			(layer "F.CrtYd")
		)
		(fp_rect
			(start -0.4318 0.9525)
			(end 0.4318 -0.9525)
			(stroke
				(width 0)
				(type default)
			)
			(fill no)
			(layer "F.Fab")
		)
		(pad "1" smd custom
			(at 0 -0.4445)
			(size 0.1524 0.1524)
			(layers "F.Cu" "F.Mask" "F.Paste")
			(net "SW_HDD4_P")
			(options
				(clearance outline)
				(anchor circle)
			)
			(primitives
				(gr_poly
					(pts
						(arc
							(start 0.3048 -0.2032)
							(mid 0.275042 -0.275042)
							(end 0.2032 -0.3048)
						)
						(arc
							(start -0.2032 -0.3048)
							(mid -0.275042 -0.275042)
							(end -0.3048 -0.2032)
						)
						(arc
							(start -0.3048 0.2032)
							(mid -0.275042 0.275042)
							(end -0.2032 0.3048)
						)
						(arc
							(start 0.2032 0.3048)
							(mid 0.275042 0.275042)
							(end 0.3048 0.2032)
						)
					)
					(width 0)
					(fill yes)
				)
			)
		)
		(pad "2" smd custom
			(at 0 0.4445)
			(size 0.1524 0.1524)
			(layers "F.Cu" "F.Mask" "F.Paste")
			(net "GND")
			(options
				(clearance outline)
				(anchor circle)
			)
			(primitives
				(gr_poly
					(pts
						(arc
							(start 0.3048 -0.2032)
							(mid 0.275042 -0.275042)
							(end 0.2032 -0.3048)
						)
						(arc
							(start -0.2032 -0.3048)
							(mid -0.275042 -0.275042)
							(end -0.3048 -0.2032)
						)
						(arc
							(start -0.3048 0.2032)
							(mid -0.275042 0.275042)
							(end -0.2032 0.3048)
						)
						(arc
							(start 0.2032 0.3048)
							(mid 0.275042 0.275042)
							(end 0.3048 0.2032)
						)
					)
					(width 0)
					(fill yes)
				)
			)
		)
	)
	(footprint ""
		(layer "F.Cu")
		(at 24.637746 -414.5407)
		(property "Reference" "TP35"
			(at 0 0 0)
			(layer "F.SilkS")
			(hide yes)
			(effects
				(font
					(size 1.27 1.27)
				)
			)
		)
		(property "Value" "TPAD32-GP"
			(at 0 -3.166364 0)
			(unlocked yes)
			(layer "F.Fab")
			(hide yes)
			(effects
				(font
					(size 1.016 1.016)
					(thickness 0.1524)
				)
			)
		)
		(property "Device Type" "TPAD32"
			(at 0 -4.690618 0)
			(unlocked yes)
			(layer "F.Fab")
			(hide yes)
			(effects
				(font
					(size 1.016 1.016)
					(thickness 0.1524)
				)
			)
		)
		(duplicate_pad_numbers_are_jumpers no)
		(fp_poly
			(pts
				(arc
					(start 0.4064 0)
					(mid -0.4064 0)
					(end 0.4064 0)
				)
			)
			(stroke
				(width 0)
				(type default)
			)
			(fill no)
			(layer "F.CrtYd")
		)
		(fp_poly
			(pts
				(arc
					(start 0.7112 0)
					(mid -0.7112 0)
					(end 0.7112 0)
				)
			)
			(stroke
				(width 0)
				(type default)
			)
			(fill no)
			(layer "F.Fab")
		)
		(pad "1" smd circle
			(at 0 0)
			(size 0.8128 0.8128)
			(layers "F.Cu" "F.Mask" "F.Paste")
			(net "ACT_HDD10")
		)
	)
	(footprint ""
		(layer "F.Cu")
		(at 217.854784 -160.117028 -90)
		(property "Reference" "C150"
			(at 0 0 270)
			(layer "F.SilkS")
			(hide yes)
			(effects
				(font
					(size 1.27 1.27)
				)
			)
		)
		(property "Value" "SCD01U50V2KX-1GP"
			(at 1.1811 -2.7051 270)
			(unlocked yes)
			(layer "F.Fab")
			(hide yes)
			(effects
				(font
					(size 1.016 1.016)
					(thickness 0.1524)
				)
			)
		)
		(property "Device Type" "C402H22"
			(at 1.1811 -4.2291 270)
			(unlocked yes)
			(layer "F.Fab")
			(hide yes)
			(effects
				(font
					(size 1.016 1.016)
					(thickness 0.1524)
				)
			)
		)
		(duplicate_pad_numbers_are_jumpers no)
		(fp_rect
			(start -0.4318 0.9525)
			(end 0.4318 -0.9525)
			(stroke
				(width 0)
				(type default)
			)
			(fill no)
			(layer "F.CrtYd")
		)
		(fp_rect
			(start -0.4318 0.9525)
			(end 0.4318 -0.9525)
			(stroke
				(width 0)
				(type default)
			)
			(fill no)
			(layer "F.Fab")
		)
		(pad "1" smd custom
			(at 0 -0.4445 270)
			(size 0.1524 0.1524)
			(layers "F.Cu" "F.Mask" "F.Paste")
			(net "SAS2X28_DRIVE_RX_N_A3")
			(options
				(clearance outline)
				(anchor circle)
			)
			(primitives
				(gr_poly
					(pts
						(arc
							(start 0.3048 -0.2032)
							(mid 0.275042 -0.275042)
							(end 0.2032 -0.3048)
						)
						(arc
							(start -0.2032 -0.3048)
							(mid -0.275042 -0.275042)
							(end -0.3048 -0.2032)
						)
						(arc
							(start -0.3048 0.2032)
							(mid -0.275042 0.275042)
							(end -0.2032 0.3048)
						)
						(arc
							(start 0.2032 0.3048)
							(mid 0.275042 0.275042)
							(end 0.3048 0.2032)
						)
					)
					(width 0)
					(fill yes)
				)
			)
		)
		(pad "2" smd custom
			(at 0 0.4445 270)
			(size 0.1524 0.1524)
			(layers "F.Cu" "F.Mask" "F.Paste")
			(net "SAS2X28_A_HDD3_RX_-")
			(options
				(clearance outline)
				(anchor circle)
			)
			(primitives
				(gr_poly
					(pts
						(arc
							(start 0.3048 -0.2032)
							(mid 0.275042 -0.275042)
							(end 0.2032 -0.3048)
						)
						(arc
							(start -0.2032 -0.3048)
							(mid -0.275042 -0.275042)
							(end -0.3048 -0.2032)
						)
						(arc
							(start -0.3048 0.2032)
							(mid -0.275042 0.275042)
							(end -0.2032 0.3048)
						)
						(arc
							(start 0.2032 0.3048)
							(mid 0.275042 0.275042)
							(end 0.3048 0.2032)
						)
					)
					(width 0)
					(fill yes)
				)
			)
		)
	)
	(footprint ""
		(layer "F.Cu")
		(at 80.390746 -395.4907 -90)
		(property "Reference" "U21"
			(at 0 0 270)
			(layer "F.SilkS")
			(hide yes)
			(effects
				(font
					(size 1.27 1.27)
				)
			)
		)
		(property "Value" "74LVC1G08GW-1-GP"
			(at -2.3368 -8.6868 270)
			(unlocked yes)
			(layer "F.Fab")
			(hide yes)
			(effects
				(font
					(size 1.016 1.016)
					(thickness 0.1524)
				)
			)
		)
		(property "Device Type" "SC70-5H44"
			(at -2.3114 -10.414 270)
			(unlocked yes)
			(layer "F.Fab")
			(hide yes)
			(effects
				(font
					(size 1.016 1.016)
					(thickness 0.1524)
				)
			)
		)
		(duplicate_pad_numbers_are_jumpers no)
		(fp_line
			(start -1.27 1.7018)
			(end -1.27 -1.7018)
			(stroke
				(width 0.1524)
				(type default)
			)
			(layer "F.SilkS")
		)
		(fp_line
			(start 1.27 1.7018)
			(end -1.27 1.7018)
			(stroke
				(width 0.1524)
				(type default)
			)
			(layer "F.SilkS")
		)
		(fp_line
			(start -1.27 -1.7018)
			(end 1.27 -1.7018)
			(stroke
				(width 0.1524)
				(type default)
			)
			(layer "F.SilkS")
		)
		(fp_line
			(start 1.27 -1.7018)
			(end 1.27 1.7018)
			(stroke
				(width 0.1524)
				(type default)
			)
			(layer "F.SilkS")
		)
		(fp_line
			(start 0.6604 -1.8034)
			(end 1.3843 -1.8034)
			(stroke
				(width 0.3302)
				(type default)
			)
			(layer "F.SilkS")
		)
		(fp_line
			(start 1.3843 -1.8034)
			(end 1.3843 -1.1176)
			(stroke
				(width 0.3302)
				(type default)
			)
			(layer "F.SilkS")
		)
		(fp_rect
			(start -1.524 1.9558)
			(end 1.524 -1.9558)
			(stroke
				(width 0)
				(type default)
			)
			(fill no)
			(layer "F.CrtYd")
		)
		(fp_poly
			(pts
				(xy -1.524 -1.9558) (xy 1.524 -1.9558) (xy 1.524 1.9558) (xy -1.524 1.9558)
			)
			(stroke
				(width 0)
				(type default)
			)
			(fill no)
			(layer "F.Fab")
		)
		(pad "1" smd rect
			(at 0.65024 -0.8255 270)
			(size 0.4064 1.2192)
			(layers "F.Cu" "F.Mask" "F.Paste")
			(net "SAS_EXP_B_PWR6")
		)
		(pad "2" smd rect
			(at 0 -0.8255 270)
			(size 0.4064 1.2192)
			(layers "F.Cu" "F.Mask" "F.Paste")
			(net "SAS_EXP_A_PWR6")
		)
		(pad "3" smd rect
			(at -0.65024 -0.8255 270)
			(size 0.4064 1.2192)
			(layers "F.Cu" "F.Mask" "F.Paste")
			(net "GND")
		)
		(pad "4" smd rect
			(at -0.65024 0.8255 270)
			(size 0.4064 1.2192)
			(layers "F.Cu" "F.Mask" "F.Paste")
			(net "DRIVE_PWR6")
		)
		(pad "5" smd rect
			(at 0.65024 0.8255 270)
			(size 0.4064 1.2192)
			(layers "F.Cu" "F.Mask" "F.Paste")
			(net "P3V3")
		)
	)
	(footprint ""
		(layer "F.Cu")
		(at 47.243746 -126.5301)
		(property "Reference" "R506"
			(at 0 0 0)
			(layer "F.SilkS")
			(hide yes)
			(effects
				(font
					(size 1.27 1.27)
				)
			)
		)
		(property "Value" "4K7R2J-2-GP"
			(at 0.064008 -3.993896 0)
			(unlocked yes)
			(layer "F.Fab")
			(hide yes)
			(effects
				(font
					(size 1.016 1.016)
					(thickness 0.1524)
				)
			)
		)
		(property "Device Type" "R402H16"
			(at 0.064008 -5.517896 0)
			(unlocked yes)
			(layer "F.Fab")
			(hide yes)
			(effects
				(font
					(size 1.016 1.016)
					(thickness 0.1524)
				)
			)
		)
		(duplicate_pad_numbers_are_jumpers no)
		(fp_line
			(start -0.508 -0.9398)
			(end -0.508 0.9398)
			(stroke
				(width 0.1524)
				(type default)
			)
			(layer "F.SilkS")
		)
		(fp_line
			(start 0.508 -0.9398)
			(end -0.508 -0.9398)
			(stroke
				(width 0.1524)
				(type default)
			)
			(layer "F.SilkS")
		)
		(fp_rect
			(start -0.508 0.9398)
			(end 0.508 -0.9398)
			(stroke
				(width 0)
				(type default)
			)
			(fill no)
			(layer "F.CrtYd")
		)
		(fp_rect
			(start -0.508 0.9398)
			(end 0.508 -0.9398)
			(stroke
				(width 0)
				(type default)
			)
			(fill no)
			(layer "F.Fab")
		)
		(pad "1" smd custom
			(at 0 -0.4445)
			(size 0.1397 0.1397)
			(layers "F.Cu" "F.Mask" "F.Paste")
			(net "P3V3")
			(options
				(clearance outline)
				(anchor circle)
			)
			(primitives
				(gr_poly
					(pts
						(arc
							(start -0.1778 -0.2794)
							(mid -0.249642 -0.249642)
							(end -0.2794 -0.1778)
						)
						(arc
							(start -0.2794 0.1778)
							(mid -0.249642 0.249642)
							(end -0.1778 0.2794)
						)
						(arc
							(start 0.1778 0.2794)
							(mid 0.249642 0.249642)
							(end 0.2794 0.1778)
						)
						(arc
							(start 0.2794 -0.1778)
							(mid 0.249642 -0.249642)
							(end 0.1778 -0.2794)
						)
					)
					(width 0)
					(fill yes)
				)
			)
		)
		(pad "2" smd custom
			(at 0 0.4445)
			(size 0.1397 0.1397)
			(layers "F.Cu" "F.Mask" "F.Paste")
			(net "SAS2X28_B_HDD13_FLT")
			(options
				(clearance outline)
				(anchor circle)
			)
			(primitives
				(gr_poly
					(pts
						(arc
							(start -0.1778 -0.2794)
							(mid -0.249642 -0.249642)
							(end -0.2794 -0.1778)
						)
						(arc
							(start -0.2794 0.1778)
							(mid -0.249642 0.249642)
							(end -0.1778 0.2794)
						)
						(arc
							(start 0.1778 0.2794)
							(mid 0.249642 0.249642)
							(end 0.2794 0.1778)
						)
						(arc
							(start 0.2794 -0.1778)
							(mid 0.249642 -0.249642)
							(end 0.1778 -0.2794)
						)
					)
					(width 0)
					(fill yes)
				)
			)
		)
	)
	(footprint ""
		(layer "F.Cu")
		(at 7.112 -23.622 180)
		(property "Reference" "R607"
			(at 0 0 180)
			(layer "F.SilkS")
			(hide yes)
			(effects
				(font
					(size 1.27 1.27)
				)
			)
		)
		(property "Value" "2R2010J-1-GP"
			(at 0.254 -8.0772 180)
			(unlocked yes)
			(layer "F.Fab")
			(hide yes)
			(effects
				(font
					(size 1.016 1.016)
					(thickness 0.1524)
				)
			)
		)
		(property "Device Type" "R2010H28"
			(at 0.254 -9.6774 180)
			(unlocked yes)
			(layer "F.Fab")
			(hide yes)
			(effects
				(font
					(size 1.016 1.016)
					(thickness 0.1524)
				)
			)
		)
		(duplicate_pad_numbers_are_jumpers no)
		(fp_line
			(start 1.651 3.302)
			(end 1.651 -3.302)
			(stroke
				(width 0.1524)
				(type default)
			)
			(layer "F.SilkS")
		)
		(fp_line
			(start 1.651 -3.302)
			(end -1.651 -3.302)
			(stroke
				(width 0.1524)
				(type default)
			)
			(layer "F.SilkS")
		)
		(fp_line
			(start -1.651 3.302)
			(end 1.651 3.302)
			(stroke
				(width 0.1524)
				(type default)
			)
			(layer "F.SilkS")
		)
		(fp_line
			(start -1.651 -3.302)
			(end -1.651 3.302)
			(stroke
				(width 0.1524)
				(type default)
			)
			(layer "F.SilkS")
		)
		(fp_rect
			(start -1.7272 -3.3782)
			(end 1.7272 3.3782)
			(stroke
				(width 0)
				(type default)
			)
			(fill no)
			(layer "F.CrtYd")
		)
		(fp_poly
			(pts
				(xy 1.7272 3.3782) (xy 1.7272 -3.3782) (xy -1.7272 -3.3782) (xy -1.7272 3.3782)
			)
			(stroke
				(width 0)
				(type default)
			)
			(fill no)
			(layer "F.Fab")
		)
		(pad "1" smd rect
			(at 0 -2.3495 180)
			(size 2.794 1.143)
			(layers "F.Cu" "F.Mask" "F.Paste")
			(net "GND")
		)
		(pad "2" smd rect
			(at 0 2.3495 180)
			(size 2.794 1.143)
			(layers "F.Cu" "F.Mask" "F.Paste")
			(net "PRSNT_B")
		)
	)
	(footprint ""
		(layer "F.Cu")
		(at 14.922246 -164.715698 90)
		(property "Reference" "R286"
			(at 0 0 90)
			(layer "F.SilkS")
			(hide yes)
			(effects
				(font
					(size 1.27 1.27)
				)
			)
		)
		(property "Value" "0R2J-2-GP"
			(at 0.064008 -3.993896 90)
			(unlocked yes)
			(layer "F.Fab")
			(hide yes)
			(effects
				(font
					(size 1.016 1.016)
					(thickness 0.1524)
				)
			)
		)
		(property "Device Type" "R402H16"
			(at 0.064008 -5.517896 90)
			(unlocked yes)
			(layer "F.Fab")
			(hide yes)
			(effects
				(font
					(size 1.016 1.016)
					(thickness 0.1524)
				)
			)
		)
		(duplicate_pad_numbers_are_jumpers no)
		(fp_line
			(start 0.508 -0.9398)
			(end -0.508 -0.9398)
			(stroke
				(width 0.1524)
				(type default)
			)
			(layer "F.SilkS")
		)
		(fp_line
			(start -0.508 -0.9398)
			(end -0.508 0.9398)
			(stroke
				(width 0.1524)
				(type default)
			)
			(layer "F.SilkS")
		)
		(fp_rect
			(start -0.508 0.9398)
			(end 0.508 -0.9398)
			(stroke
				(width 0)
				(type default)
			)
			(fill no)
			(layer "F.CrtYd")
		)
		(fp_rect
			(start -0.508 0.9398)
			(end 0.508 -0.9398)
			(stroke
				(width 0)
				(type default)
			)
			(fill no)
			(layer "F.Fab")
		)
		(pad "1" smd custom
			(at 0 -0.4445 90)
			(size 0.1397 0.1397)
			(layers "F.Cu" "F.Mask" "F.Paste")
			(net "FLT_NET_HDD13")
			(options
				(clearance outline)
				(anchor circle)
			)
			(primitives
				(gr_poly
					(pts
						(arc
							(start -0.1778 -0.2794)
							(mid -0.249642 -0.249642)
							(end -0.2794 -0.1778)
						)
						(arc
							(start -0.2794 0.1778)
							(mid -0.249642 0.249642)
							(end -0.1778 0.2794)
						)
						(arc
							(start 0.1778 0.2794)
							(mid 0.249642 0.249642)
							(end 0.2794 0.1778)
						)
						(arc
							(start 0.2794 -0.1778)
							(mid 0.249642 -0.249642)
							(end 0.1778 -0.2794)
						)
					)
					(width 0)
					(fill yes)
				)
			)
		)
		(pad "2" smd custom
			(at 0 0.4445 90)
			(size 0.1397 0.1397)
			(layers "F.Cu" "F.Mask" "F.Paste")
			(net "FLT_HDD13_DRIVE")
			(options
				(clearance outline)
				(anchor circle)
			)
			(primitives
				(gr_poly
					(pts
						(arc
							(start -0.1778 -0.2794)
							(mid -0.249642 -0.249642)
							(end -0.2794 -0.1778)
						)
						(arc
							(start -0.2794 0.1778)
							(mid -0.249642 0.249642)
							(end -0.1778 0.2794)
						)
						(arc
							(start 0.1778 0.2794)
							(mid 0.249642 0.249642)
							(end 0.2794 0.1778)
						)
						(arc
							(start 0.2794 -0.1778)
							(mid 0.249642 -0.249642)
							(end 0.1778 -0.2794)
						)
					)
					(width 0)
					(fill yes)
				)
			)
		)
	)
	(footprint ""
		(layer "F.Cu")
		(at 60.3758 -497.6114 180)
		(property "Reference" "C194"
			(at 0 0 180)
			(layer "F.SilkS")
			(hide yes)
			(effects
				(font
					(size 1.27 1.27)
				)
			)
		)
		(property "Value" "SC10U25V6KX-1GP"
			(at -0.0762 -5.1308 180)
			(unlocked yes)
			(layer "F.Fab")
			(hide yes)
			(effects
				(font
					(size 1.016 1.016)
					(thickness 0.1524)
				)
			)
		)
		(property "Device Type" "C1206H71"
			(at -0.127 -6.6548 180)
			(unlocked yes)
			(layer "F.Fab")
			(hide yes)
			(effects
				(font
					(size 1.016 1.016)
					(thickness 0.1524)
				)
			)
		)
		(duplicate_pad_numbers_are_jumpers no)
		(fp_line
			(start 1.016 2.2352)
			(end -1.016 2.2352)
			(stroke
				(width 0.1524)
				(type default)
			)
			(layer "F.SilkS")
		)
		(fp_line
			(start 1.016 0.8382)
			(end 1.016 2.2352)
			(stroke
				(width 0.1524)
				(type default)
			)
			(layer "F.SilkS")
		)
		(fp_line
			(start 1.016 -2.2352)
			(end 1.016 -0.8382)
			(stroke
				(width 0.1524)
				(type default)
			)
			(layer "F.SilkS")
		)
		(fp_line
			(start -1.016 2.2352)
			(end -1.016 0.8382)
			(stroke
				(width 0.1524)
				(type default)
			)
			(layer "F.SilkS")
		)
		(fp_line
			(start -1.016 -0.8382)
			(end -1.016 -2.2352)
			(stroke
				(width 0.1524)
				(type default)
			)
			(layer "F.SilkS")
		)
		(fp_line
			(start -1.016 -2.2352)
			(end 1.016 -2.2352)
			(stroke
				(width 0.1524)
				(type default)
			)
			(layer "F.SilkS")
		)
		(fp_rect
			(start -1.0922 2.3114)
			(end 1.0922 -2.3114)
			(stroke
				(width 0)
				(type default)
			)
			(fill no)
			(layer "F.CrtYd")
		)
		(fp_poly
			(pts
				(xy 1.0922 -2.3114) (xy 1.0922 2.3114) (xy -1.0922 2.3114) (xy -1.0922 -2.3114)
			)
			(stroke
				(width 0)
				(type default)
			)
			(fill no)
			(layer "F.Fab")
		)
		(pad "1" smd rect
			(at 0 -1.397 180)
			(size 1.651 1.27)
			(layers "F.Cu" "F.Mask" "F.Paste")
			(net "P12V_HDD5")
		)
		(pad "2" smd rect
			(at 0 1.397 180)
			(size 1.651 1.27)
			(layers "F.Cu" "F.Mask" "F.Paste")
			(net "GND")
		)
	)
)
